# S9S_MB_2U (Grand Teton) — schematic parts with pin connectivity, parts 1628–1636 of 6093; source: Cadence DE-HDL packaged netlist (pstxprt.dat, pstxnet.dat, pstchip.dat)

J41  SCONN168_ME1016810202011  IO  pkg CON_F168S2H7D_P0-6W2-95_LUH  page 240
  A1  GND_A1  POWER  = SMB_OCP_SFF_3V3AUX_SCL_R0
  A2  GND_A2  POWER  = SMB_OCP_SFF_3V3AUX_SDA_R0
  A3  GND_A3  POWER  = SMB_HOST_3V3AUX_SCL_R0
  A4  GND_A4  POWER  = SMB_HOST_3V3AUX_SDA_R0
  A5  GND_A5  POWER  = SMB_VR_3V3AUX_SCL_R0
  A6  GND_A6  POWER  = SMB_VR_3V3AUX_SDA_R0
  A7  SMCLK  OUT  = SMB_SML1_PMBUS_3V3AUX_PCH_SCL_R
  A8  SMDAT  BI  = SMB_SML1_PMBUS_3V3AUX_PCH_SDA_R
  A9  \smrst#\  OUT  = I3C_BMC_SWB_SCL
  A10  \prsnta#\  OUT  = I3C_BMC_SWB_SDA
  A11  \perst1#\  OUT  = SMB_OCP_V3_2_3V3AUX_SCL_R0
  A12  \prsntb2#\  IN  = SMB_OCP_V3_2_3V3AUX_SDA_R0
  A13  GND_A13  POWER  = GND
  A14  REFCLKN1  OUT  = CLK_100M_BMC_P3E_DP_R
  A15  REFCLKP1  OUT  = CLK_100M_BMC_P3E_DN_R
  A16  GND_A16  POWER  = GND
  A17  PERN0  IN  = P3E_PCH_BMC_TX_C_DP
  A18  PERP0  IN  = P3E_PCH_BMC_TX_C_DN
  A19  GND_A19  POWER  = GND
  A20  PERN1  IN  = P3E_PCH_BMC_RX_DP
  A21  PERP1  IN  = P3E_PCH_BMC_RX_DN
  A22  GND_A22  POWER  = GND
  A23  PERN2  IN  = SMB_PCIE0_3V3AUX_SCL
  A24  PERP2  IN  = SMB_PCIE0_3V3AUX_SDA
  A25  GND_A25  POWER  = SMB_SML0_3V3AUX_SCL_R1
  A26  PERN3  IN  = SMB_SML0_3V3AUX_SDA_R1
  A27  PERP3  IN  = SMB_1_PLD_3V3AUX_SCL_R3
  A28  GND_A28  POWER  = SMB_1_PLD_3V3AUX_SDA_R3
  A29  GND_A29  POWER  = SMB_FAN_3V3AUX_SCL
  A30  PERN4  IN  = SMB_FAN_3V3AUX_SDA
  A31  PERP4  IN  = SMB_PCIE2_3V3AUX_SCL_R0
  A32  GND_A32  POWER  = SMB_PCIE2_3V3AUX_SDA_R0
  A33  PERN5  IN  = GND
  A34  PERP5  IN  = JTAG_BMC_TCK
  A35  GND_A35  POWER  = JTAG_BMC_TMS
  A36  PERN6  IN  = JTAG_BMC_TDI
  A37  PERP6  IN  = JTAG_BMC_TDO
  A38  GND_A38  POWER  = SMB_PCIE3_3V3AUX_SCL_R
  A39  PERN7  IN  = SMB_PCIE3_3V3AUX_SDA_R
  A40  PERP7  IN  = SMB_S3M_CPU_3V3AUX_SCL_R0
  A41  GND_A41  POWER  = SMB_S3M_CPU_3V3AUX_SDA_R0
  A42  \prsntb1#\  IN  = GND
  A43  GND_A43  POWER  = FM_JTAG_BMC_MUX_SEL_FROM_BMC_R2
  A44  PERN8  IN  = PWRGD_PS_PWROK_R
  A45  PERP8  IN  = TP_HPM_STBY_EN
  A46  GND_A46  POWER  = RST_MB_STBY_N
  A47  PERN9  IN  = FM_BMC_PWRBTN_OUT_R_N
  A48  PERP9  IN  = PWRGD_SYS_PWROK
  A49  GND_A49  POWER  = JTAG_BMC_DBP_PREQ_N
  A50  PERN10  IN  = JTAG_DBP_BMC_PRDY_N
  A51  PERP10  IN  = RST_PLTRST_B_N
  A52  GND_A52  POWER  = FM_UARTSW_MSB_R
  A53  PERN11  IN  = ROT_P1_RST_IND_N
  A54  PERP11  IN  = FM_BMC_INTRUDER_N
  A55  GND_A55  POWER  = FM_UARTSW_LSB_R
  A56  PERN12  IN  = IRQ0_A57
  A57  PERP12  IN  = FM_SCM_PRSNT1_N
  A58  GND_A58  POWER  = GND
  A59  PERN13  IN  = USB3_PCH_RX_DP<4>
  A60  PERP13  IN  = USB3_PCH_RX_DN<4>
  A61  GND_A61  POWER  = GND
  A62  PERN14  IN  = TP_PCIE_HPM_RXP<1>
  A63  PERP14  IN  = TP_PCIE_HPM_RXN<1>
  A64  GND_A64  POWER  = GND
  A65  PERN15  IN  = P2E_MB_BMC_RX_BUF_DP<0>
  A66  PERP15  IN  = P2E_MB_BMC_RX_BUF_DN<0>
  A67  GND_A67  POWER  = GND
  A68  USB_DATN  BI  = CLK_100M_BMC_RC_DP
  A69  USB_DATP  BI  = CLK_100M_BMC_RC_DN
  A70  \pwrbrk0#\  BI  = GND
  B1  \+12v_edge_b1\  POWER  = ESPI_HOST_LPC_BMC_CLK
  B2  \+12v_edge_b2\  POWER  = ESPI_HOST_LPC_BMC_LFRAME_N
  B3  \+12v_edge_b3\  POWER  = IRQ_ESPI_LPC_SERIRQ_ALERT_R_N
  B4  \+12v_edge_b4\  POWER  = ESPI_BMC_LPC_RST_N
  B5  \+12v_edge_b5\  POWER  = ESPI_LPC_LAD0_IO0
  B6  \+12v_edge_b6\  POWER  = ESPI_LPC_LAD0_IO1
  B7  \bif0#\  OUT  = ESPI_LPC_LAD0_IO2
  B8  \bif1#\  OUT  = ESPI_LPC_LAD0_IO3
  B9  \bif2#\  OUT  = FM_LPC_ESPI_SEL
  B10  \perst0#\  OUT  = GND
  B11  \+3.3v_edge\  POWER  = SPI_SYS_CLK
  B12  AUX_PWR_EN  OUT  = SPI_SYS_CS0_N
  B13  GND_B13  POWER  = SPI_SYS_MOSI
  B14  REFCLKN0  IN  = SPI_SYS_MISO
  B15  REFCLKP0  OUT  = SPI_SYS_WP_IO2
  B16  GND_B16  POWER  = SPI_SYS_HOLD_IO3
  B17  PETN0  OUT  = GND
  B18  PETP0  OUT  = CLK_50M_RMII_BMC_OCP
  B19  GND_B19  POWER  = RMII_OCP_BMC_CRSDV
  B20  PETN1  OUT  = RMII_BMC_OCP_TX_EN
  B21  PETP1  OUT  = RMII_BMC_OCP_TXD_0
  B22  GND_B22  POWER  = RMII_BMC_OCP_TXD_1
  B23  PETN2  OUT  = RMII_BMC_OCP_RX_ER
  B24  PETP2  OUT  = RMII_OCP_BMC_RXD_0
  B25  GND_B25  POWER  = RMII_OCP_BMC_RXD_1
  B26  PETN3  OUT  = GND
  B27  PETP3  OUT  = PECI_BMC
  B28  GND_B28  POWER  = PVCCIO_PECI_BMC
  B29  GND_B29  POWER  = SGPIO_DO_0
  B30  PETN4  OUT  = SGPIO_CLK_0
  B31  PETP4  OUT  = SGPIO_DI_0
  B32  GND_B32  POWER  = SGPIO_LD_0
  B33  PETN5  OUT  = GND
  B34  PETP5  OUT  = SGPIO_DO_1
  B35  GND_B35  POWER  = SGPIO_CLK_1
  B36  PETN6  OUT  = SGPIO_DI_1
  B37  PETP6  OUT  = SGPIO_LD_1
  B38  GND_B38  POWER  = GND
  B39  PETN7  OUT  = RST_SGPIO_RESET_N
  B40  PETP7  OUT  = IRQ_SGPIO_INTR_N
  B41  GND_B41  POWER  = P3V_BAT_R1
  B42  \prsntb0#\  IN  = FM_AC_PWR_BTN_N
  B43  GND_B43  POWER  = TP_SPI_2_PLD_CLK
  B44  PETN8  OUT  = TP_SPI_2_PLD_CS_N
  B45  PETP8  OUT  = TP_SPI_2_PLD_IO0
  B46  GND_B46  POWER  = TP_SPI_2_PLD_IO1
  B47  PETN9  OUT  = TP_SPI_2_PLD_IO2
  B48  PETP9  OUT  = TP_SPI_2_PLD_IO3
  B49  GND_B49  POWER  = GND
  B50  PETN10  OUT  = USB2_HOST_BMC_B_DP
  B51  PETP10  OUT  = USB2_HOST_BMC_B_DN
  B52  GND_B52  POWER  = GND
  B53  PETN11  OUT  = USB2_8_DP
  B54  PETP11  OUT  = USB2_8_DN
  B55  GND_B55  POWER  = GND
  B56  PETN12  OUT  = USB2_HUB_2_BUF_EXT_DP
  B57  PETP12  OUT  = USB2_HUB_2_BUF_EXT_DN
  B58  GND_B58  POWER  = GND
  B59  PETN13  OUT  = USB3_PCH_TX_BUF_C_DP<4>
  B60  PETP13  OUT  = USB3_PCH_TX_BUF_C_DN<4>
  B61  GND_B61  POWER  = GND
  B62  PETN14  OUT  = TP_PCIE_HPM_TXP<1>
  B63  PETP14  OUT  = TP_PCIE_HPM_TXN<1>
  B64  GND_B64  POWER  = GND
  B65  PETN15  OUT  = P2E_MB_BMC_TX_C_DP<0>
  B66  PETP15  OUT  = P2E_MB_BMC_TX_C_DN<0>
  B67  GND_B67  POWER  = GND
  B68  RFU1_NC_B68  TRI  = TP_PCIE_HPM_TXP<3>
  B69  RFU1_NC_B69  TRI  = TP_PCIE_HPM_TXN<3>
  B70  \prsntb3#\  IN  = GND
  G1  G1  POWER  = GND
  G2  G2  POWER  = GND
  G3  G3  POWER  = GND
  G4  G4  POWER  = GND
  G5  G5  POWER  = GND
  OA1  \perst2#\  OUT  = P12V_SCM
  OA2  \perst3#\  OUT  = P12V_SCM
  OA3  \wake#\  IN  = GND
  OA4  RBT_ARB_IN  IN  = GND
  OA5  RBT_ARB_OUT  OUT  = I3C_SPD_DDRABCD_CPU0_BMC_R_SCL
  OA6  SLOT_ID1  OUT  = I3C_SPD_DDRABCD_CPU0_BMC_R_SDA
  OA7  RBT_TX_EN  OUT  = I3C_SPD_DDREFGH_CPU0_BMC_R_SCL
  OA8  RBT_TXD1  OUT  = I3C_SPD_DDREFGH_CPU0_BMC_R_SDA
  OA9  RBT_TXD0  OUT  = I3C_SPD_DDRABCD_CPU1_BMC_R_SCL
  OA10  GND_OA10  POWER  = I3C_SPD_DDRABCD_CPU1_BMC_R_SDA
  OA11  REFCLKN3  OUT  = I3C_SPD_DDREFGH_CPU1_BMC_R_SCL
  OA12  REFCLKP3  OUT  = I3C_SPD_DDREFGH_CPU1_BMC_R_SDA
  OA13  GND_OA13  POWER  = GND
  OA14  RBT_CLK_IN  OUT  = VIRTUAL_RESEAT
  OB1  NIC_PWR_GOOD  IN  = P12V_SCM
  OB2  MAIN_PWR_EN  OUT  = P12V_SCM
  OB3  \ld#\  OUT  = PRSNT0_N
  OB4  DATA_IN  IN  = GND
  OB5  DATA_OUT  OUT  = UART_BMC_BIC_TX
  OB6  CLK  OUT  = UART_BMC_BIC_BUF_RX
  OB7  SLOT_ID0  OUT  = GND
  OB8  RBT_RXD1  IN  = USB2_7_R_DP
  OB9  RBT_RXD0  IN  = USB2_7_R_DN
  OB10  GND_OB10  POWER  = GND
  OB11  REFCLKN2  OUT  = RST_SRST_PLD_BMC_N
  OB12  REFCLKP2  OUT  = SPI_TPM_CS_N
  OB13  GND_OB13  POWER  = H_CPU_CATERR_LVC2_BMC_N
  OB14  RBT_CRS_DV  OUT  = FM_SOL_UART_CH_SEL_R

J42  SCONN60_ASP21410801  SCONN60_ASP-214108-01 IO  pkg CON_60S2H2D4S_P0-5_LDV  page 131
  1  \1\  BI  = P1V05_PCH_AUX
  2  \2\  BI  = JTAG_DBP_TMS_R
  3  \3\  BI  = JTAG_DBP_CPU_GTL_TCK_R
  4  \4\  BI  = JTAG_DBP_TDO_R
  5  \5\  BI  = JTAG_DBP_TDI_R
  6  \6\  BI  = JTAG_RST_DBP_RST_CO_N
  7  \7\  BI  = JTAG_DBP_PMODE
  8  \8\  BI  = PD_TRST_P3
  9  \9\  BI  = NC_MIPI60_P9
  10  \10\  BI  = JTAG_DBP_PREQ_N_R
  11  \11\  BI  = JTAG_DBP_PRDY_R1_N
  12  \12\  BI  = P1V8_PCH_AUX
  13  \13\  BI  = JTAG_TRC_PCH_PTI0_CLK
  14  \14\  BI  = GND
  15  \15\  BI  = JTAG_DBP_PCH_DEBUG_CONSENT_N
  16  \16\  BI  = GND
  17  \17\  BI  = JTAG_DBP_PRESENT_R_N
  18  \18\  BI  = NC_DBP_P18
  19  \19\  BI  = JTAG_TRC_PCH_PTI<0>
  20  \20\  BI  = NC_DBP_P20
  21  \21\  BI  = JTAG_TRC_PCH_PTI<1>
  22  \22\  BI  = NC_DBP_P22
  23  \23\  BI  = JTAG_TRC_PCH_PTI<2>
  24  \24\  BI  = NC_DBP_P24
  25  \25\  BI  = JTAG_TRC_PCH_PTI<3>
  26  \26\  BI  = NC_DBP_P26
  27  \27\  BI  = JTAG_TRC_PCH_PTI<4>
  28  \28\  BI  = NC_DBP_P28
  29  \29\  BI  = JTAG_TRC_PCH_PTI<5>
  30  \30\  BI  = NC_DBP_P30
  31  \31\  BI  = JTAG_TRC_PCH_PTI<6>
  32  \32\  BI  = NC_DBP_P32
  33  \33\  BI  = JTAG_TRC_PCH_PTI<7>
  34  \34\  BI  = NC_DBP_P34
  35  \35\  BI  = JTAG_TRC_PCH_PTI<8>
  36  \36\  BI  = JTAG_DBP_BOOT_HALT_N
  37  \37\  BI  = JTAG_TRC_PCH_PTI<9>
  38  \38\  BI  = FM_CPU_FBRK_DEBUG_N
  39  \39\  BI  = JTAG_TRC_PCH_PTI<10>
  40  \40\  BI  = JTAG_DBP_POWER_BTN_N
  41  \41\  BI  = JTAG_TRC_PCH_PTI<11>
  42  \42\  BI  = JTAG_RST_DBP_RSMRST_N
  43  \43\  BI  = JTAG_TRC_PCH_PTI<12>
  44  \44\  BI  = NC_DBP_P44
  45  \45\  BI  = JTAG_TRC_PCH_PTI<13>
  46  \46\  BI  = NC_DBP_P46
  47  \47\  BI  = JTAG_TRC_PCH_PTI<14>
  48  \48\  BI  = SMB_HOST_3V3AUX_XDP_R_SCL
  49  \49\  BI  = JTAG_TRC_PCH_PTI<15>
  50  \50\  BI  = SMB_HOST_3V3AUX_XDP_R_SDA
  51  \51\  BI  = JTAG_DBP_TCK_R_TCK
  52  \52\  BI  = P3V3_AUX
  53  \53\  BI  = JTAG_DBP_CPU_HOOK9_MBP3_GTL_N
  54  \54\  BI  = NC_DBP_P54
  55  \55\  BI  = JTAG_DBP_CPU_HOOK8_MBP2_GTL_N
  56  \56\  BI  = NC_DBP_P56
  57  \57\  BI  = GND
  58  \58\  BI  = GND
  59  \59\  BI  = JTAG_TRC_PCH_PTI1_CLK
  60  \60\  BI  = GND
  G1  G1  POWER  = GND
  G2  G2  POWER  = GND
  G3  G3  POWER  = GND
  G4  G4  POWER  = GND

J43  CONN8_210HP1080BR1  CONN8_210-HP1-080BR1 IO  pkg HEADER1X8XE  page 221
  1  \1\  BI  = P3V3_AUX_BMC_D
  2  \2\  BI  = JTAG_BMC_PLD_TDO
  3  \3\  BI  = JTAG_BMC_PLD_TDI
  4  \4\  BI  = TP_PLD_CONN_P4
  5  \5\  BI  = TP_PLD_CONN_P5
  6  \6\  BI  = JTAG_BMC_PLD_TMS
  7  \7\  BI  = GND
  8  \8\  BI  = JTAG_BMC_PLD_TCK

J45  CONN60_101062636003K02LF  CONN60_10106263-6003K02LF IO  pkg HSD_M60D4H2D_P2-54W2-54_LDHXB  page 245
  A1  A1  BI  = TP_J45_A1
  A2  A2  BI  = FM_AC_PWR_BTN_PDB_N
  A3  A3  BI  = P3V3_PDB_AUX_ADC
  B1  B1  BI  = RST_SMB_SWITCH_R_N
  B2  B2  BI  = PWRGD_P3V3_AUX_PDB_BUF
  B3  B3  BI  = GND
  C1  C1  BI  = SMB_FAN_3V3AUX_BUF_R_SCL
  C2  C2  BI  = SMB_FAN_3V3AUX_BUF_R_SDA
  C3  C3  BI  = HPDB_HSC_PWRGD_R
  D1  D1  BI  = FM_FAN_PWR_EN_R
  D2  D2  BI  = FM_GPU_HSC_EN_BUF_R1
  D3  D3  BI  = PDB_PRSNT_N
  P1_1  P1_1  POWER  = GND
  P1_2  P1_2  POWER  = GND
  P1_3  P1_3  POWER  = GND
  P1_4  P1_4  POWER  = GND
  P1_5  P1_5  POWER  = GND
  P1_6  P1_6  POWER  = GND
  P1_7  P1_7  POWER  = GND
  P1_8  P1_8  POWER  = GND
  P2_1  P2_1  POWER  = GND
  P2_2  P2_2  POWER  = GND
  P2_3  P2_3  POWER  = GND
  P2_4  P2_4  POWER  = GND
  P2_5  P2_5  POWER  = GND
  P2_6  P2_6  POWER  = GND
  P2_7  P2_7  POWER  = GND
  P2_8  P2_8  POWER  = GND
  P3_1  P3_1  POWER  = GND
  P3_2  P3_2  POWER  = GND
  P3_3  P3_3  POWER  = GND
  P3_4  P3_4  POWER  = GND
  P3_5  P3_5  POWER  = GND
  P3_6  P3_6  POWER  = GND
  P3_7  P3_7  POWER  = GND
  P3_8  P3_8  POWER  = GND
  P4_1  P4_1  POWER  = P12V_PSU
  P4_2  P4_2  POWER  = P12V_PSU
  P4_3  P4_3  POWER  = P12V_PSU
  P4_4  P4_4  POWER  = P12V_PSU
  P4_5  P4_5  POWER  = P12V_PSU
  P4_6  P4_6  POWER  = P12V_PSU
  P4_7  P4_7  POWER  = P12V_PSU
  P4_8  P4_8  POWER  = P12V_PSU
  P5_1  P5_1  POWER  = P12V_PSU
  P5_2  P5_2  POWER  = P12V_PSU
  P5_3  P5_3  POWER  = P12V_PSU
  P5_4  P5_4  POWER  = P12V_PSU
  P5_5  P5_5  POWER  = P12V_PSU
  P5_6  P5_6  POWER  = P12V_PSU
  P5_7  P5_7  POWER  = P12V_PSU
  P5_8  P5_8  POWER  = P12V_PSU
  P6_1  P6_1  POWER  = P12V_PSU
  P6_2  P6_2  POWER  = P12V_PSU
  P6_3  P6_3  POWER  = P12V_PSU
  P6_4  P6_4  POWER  = P12V_PSU
  P6_5  P6_5  POWER  = P12V_PSU
  P6_6  P6_6  POWER  = P12V_PSU
  P6_7  P6_7  POWER  = P12V_PSU
  P6_8  P6_8  POWER  = P12V_PSU

J59  SCONN75K_APCI0155P004A  SCONN75K_APCI0155-P004A EMPTY  pkg CON_F67S2H2D2S_P0-5W7-55_LUVXB_H270  page 190
  1  GND1  POWER  = PCIE_M2_SSD0_PRSNT_N
  2  \3.3v_1\  POWER  = P3V3_M2_0
  3  GND2  POWER  = GND
  4  \3.3v_2\  POWER  = P3V3_M2_0
  5  PERN3  BI  = P3E_PCH_M2_RX_DN<0>
  6  NC1  TRI  = NC_M2_0_NC1
  7  PERP3  BI  = P3E_PCH_M2_RX_DP<0>
  8  NC2  TRI  = NC_M2_0_NC2
  9  GND3  POWER  = GND
  10  \das_dss#||led1#\  BI  = LED_M2_SSD_0_ACT_N
  11  PETN3  BI  = P3E_PCH_M2_TX_C_DP<0>
  12  \3.3v_3\  POWER  = P3V3_M2_0
  13  PETP3  BI  = P3E_PCH_M2_TX_C_DN<0>
  14  \3.3v_4\  POWER  = P3V3_M2_0
  15  GND4  POWER  = GND
  16  \3.3v_5\  POWER  = P3V3_M2_0
  17  PERN2  BI  = P3E_PCH_M2_RX_DN<1>
  18  \3.3v_6\  POWER  = P3V3_M2_0
  19  PERP2  BI  = P3E_PCH_M2_RX_DP<1>
  20  NC3  TRI  = NC_M2_0_NC3
  21  GND5  POWER  = GND
  22  NC4  TRI  = NC_M2_0_NC4
  23  PETN2  BI  = P3E_PCH_M2_TX_C_DP<1>
  24  NC5  TRI  = NC_M2_0_NC5
  25  PETP2  BI  = P3E_PCH_M2_TX_C_DN<1>
  26  NC6  TRI  = NC_M2_0_NC6
  27  GND6  POWER  = GND
  28  NC7  TRI  = NC_M2_0_NC7
  29  PERN1  BI  = P3E_PCH_M2_RX_DN<2>
  30  NC8  TRI  = NC_M2_0_NC8
  31  PERP1  BI  = P3E_PCH_M2_RX_DP<2>
  32  NC9  TRI  = NC_M2_0_NC9
  33  GND7  POWER  = GND
  34  NC10  TRI  = NC_M2_0_NC10
  35  PETN1  BI  = P3E_PCH_M2_TX_C_DP<2>
  36  NC11  TRI  = NC_M2_0_NC11
  37  PETP1  BI  = P3E_PCH_M2_TX_C_DN<2>
  38  DEVSLP  IN  = PD_M2_0_DEVSLP
  39  GND8  POWER  = GND
  40  NC12  TRI  = SMB_M2_P0_1V8AUX_SCL
  41  \pern0||sata-b+\  BI  = P3E_PCH_M2_RX_DN<3>
  42  NC13  TRI  = SMB_M2_P0_1V8AUX_SDA
  43  \perp0||sata-b-\  BI  = P3E_PCH_M2_RX_DP<3>
  44  NC14  TRI  = NC_M2_0_NC14
  45  GND9  POWER  = GND
  46  NC15  TRI  = NC_M2_0_NC15
  47  \petn0||sata-a-\  BI  = P3E_PCH_M2_TX_C_DP<3>
  48  NC16  TRI  = NC_M2_0_NC16
  49  \petp0||sata-a+\  BI  = P3E_PCH_M2_TX_C_DN<3>
  50  \perst#\  IN  = RST_PCIE_PCH_DEV_0_N
  51  GND10  POWER  = GND
  52  \clkreq#\  BI  = M2_SSD0_CLKREQ_EN_N_BUF
  53  REFCLKN  IN  = CLK_100M_PE_M2_0_DN
  54  \pewake#\  BI  = M2_0_PEWAKE_N
  55  REFCLKP  IN  = CLK_100M_PE_M2_0_DP
  56  NC17  TRI  = NC_M2_0_NC17
  57  GND11  POWER  = GND
  58  NC18  TRI  = NC_M2_0_NC18
  67  NC19  TRI  = NC_M2_0_NC19
  68  SUSCLK  IN  = NC_M2_0_SUSCLK
  69  PEDET  OUT  = FM_M2_SSD_0_PEDET
  70  \3.3v_7\  POWER  = P3V3_M2_0
  71  GND12  POWER  = GND
  72  \3.3v_8\  POWER  = P3V3_M2_0
  73  GND13  POWER  = GND
  74  \3.3v_9\  POWER  = P3V3_M2_0
  75  GND14  POWER  = GND
  G1  G1  POWER  = GND
  G2  G2  POWER  = GND

J63  PICOPROBE_BXA  DELTA-L 4.0 EMPTY  pkg TRIANG_LAUNCH_3PXB  page 308
  1  \1_p\  POWER  = DELTA_L_85_5INCH_TOP_DP
  2  \2_n\  POWER  = DELTA_L_85_5INCH_TOP_DN
  3  \3_g\  POWER  = DELTA_L_GND_1

J64  PICOPROBE_BXA  DELTA-L 4.0 EMPTY  pkg TRIANG_LAUNCH_3PXB  page 308
  1  \1_p\  POWER  = DELTA_L_85_5INCH_BOT_DP
  2  \2_n\  POWER  = DELTA_L_85_5INCH_BOT_DN
  3  \3_g\  POWER  = DELTA_L_GND_1

J65  PICOPROBE_BXA  DELTA-L 4.0 EMPTY  pkg TRIANG_LAUNCH_3PXB  page 308
  1  \1_p\  POWER  = DELTA_L_85_5INCH_IN1_DP
  2  \2_n\  POWER  = DELTA_L_85_5INCH_IN1_DN
  3  \3_g\  POWER  = DELTA_L_GND_1

J66  PICOPROBE_BXA  DELTA-L 4.0 EMPTY  pkg TRIANG_LAUNCH_3PXB  page 308
  1  \1_p\  POWER  = DELTA_L_85_5INCH_IN2_DP
  2  \2_n\  POWER  = DELTA_L_85_5INCH_IN2_DN
  3  \3_g\  POWER  = DELTA_L_GND_1
